# S9S_MB_2U (Grand Teton) — schematic netlist excerpt (pin names and nets, part order shuffled) for the footprints in the layout excerpt that follows; sources: Cadence DE-HDL packaged netlist, KiCad conversion of 03242023_DA0F0TMBIJ0_F0T_Motherboard_J_brd_V01_OCP.brd

R1374  Q_RES  1K 1% CHIP  pkg 0402LF  page 134 : A = PD_JTAG_BMC_NTRST_N ; B = GND

U272  LM75BD  IC  pkg SO8_1-27_4-9X3-9  page 170
  SDA  = SMB_LM75_2_3V3AUX_SDA_R1
  SCL  = SMB_LM75_2_3V3AUX_SCL_R1
  OS  = FM_LM75_2_ALERT_N
  GND  = GND
  A2  = U272_2_ADD2
  A1  = U272_2_ADD1
  A0  = U272_2_ADD0
  VCC  = P3V3_AUX

(kicad_pcb
	(version 20260206)
	(generator "pcbnew")
	(generator_version "10.0")
	(general
		(thickness 1.6)
		(legacy_teardrops no)
	)
	(paper "A4")
	(title_block
		(title "03242023_DA0F0TMBIJ0_F0T_Motherboard_J_brd_V01_OCP.brd")
		(comment 1 "Grand Teton / footprints 2284-2285 of 6105")
	)
	(layers
		(0 "F.Cu" signal "TOP")
		(4 "In1.Cu" signal "GND")
		(6 "In2.Cu" signal "IN1")
		(8 "In3.Cu" signal "GND1")
		(10 "In4.Cu" signal "IN2")
		(12 "In5.Cu" signal "GND2")
		(14 "In6.Cu" signal "IN3")
		(16 "In7.Cu" signal "GND3")
		(18 "In8.Cu" signal "VCC")
		(20 "In9.Cu" signal "VCC1")
		(22 "In10.Cu" signal "GND4")
		(24 "In11.Cu" signal "IN4")
		(26 "In12.Cu" signal "GND5")
		(28 "In13.Cu" signal "IN5")
		(30 "In14.Cu" signal "GND6")
		(32 "In15.Cu" signal "IN6")
		(34 "In16.Cu" signal "GND7")
		(2 "B.Cu" signal "BOTTOM")
		(9 "F.Adhes" user "F.Adhesive")
		(11 "B.Adhes" user "B.Adhesive")
		(13 "F.Paste" user "Package Geometry/Pastemask Top")
		(15 "B.Paste" user "Package Geometry/Pastemask Bottom")
		(5 "F.SilkS" user "Ref Des/Silkscreen Top")
		(7 "B.SilkS" user "Ref Des/Silkscreen Bottom")
		(1 "F.Mask" user "Board Geometry/Soldermask Top")
		(3 "B.Mask" user "Board Geometry/Soldermask Bottom")
		(17 "Dwgs.User" user "User.Drawings")
		(19 "Cmts.User" user "User.Comments")
		(21 "Eco1.User" user "User.Eco1")
		(23 "Eco2.User" user "User.Eco2")
		(25 "Edge.Cuts" user "Board Geometry/Outline")
		(27 "Margin" user)
		(31 "F.CrtYd" user "Package Geometry/Place Bound Top")
		(29 "B.CrtYd" user "Package Geometry/Place Bound Bottom")
		(35 "F.Fab" user "Ref Des/Assembly Top")
		(33 "B.Fab" user "Ref Des/Assembly Bottom")
	)
	(footprint ""
		(layer "F.Cu")
		(at 96.57588 -57.241948 180)
		(property "Reference" "R1374"
			(at 0 0 180)
			(layer "F.SilkS")
			(hide yes)
			(effects
				(font
					(size 1.27 1.27)
				)
			)
		)
		(property "Value" ""
			(at 0 0 180)
			(layer "F.Fab")
			(effects
				(font
					(size 1.27 1.27)
				)
			)
		)
		(duplicate_pad_numbers_are_jumpers no)
		(fp_line
			(start 0.7874 0.4064)
			(end -0.7874 0.4064)
			(stroke
				(width 0.1524)
				(type default)
			)
			(layer "F.SilkS")
		)
		(fp_line
			(start 0.7874 -0.4064)
			(end 0.7874 0.4064)
			(stroke
				(width 0.1524)
				(type default)
			)
			(layer "F.SilkS")
		)
		(fp_line
			(start -0.7874 0.4064)
			(end -0.7874 -0.4064)
			(stroke
				(width 0.1524)
				(type default)
			)
			(layer "F.SilkS")
		)
		(fp_line
			(start -0.7874 -0.4064)
			(end 0.7874 -0.4064)
			(stroke
				(width 0.1524)
				(type default)
			)
			(layer "F.SilkS")
		)
		(fp_line
			(start 0.67945 0.3048)
			(end 0.120396 0.3048)
			(stroke
				(width 0.1)
				(type default)
			)
			(layer "F.Fab")
		)
		(fp_line
			(start 0.67945 -0.3048)
			(end 0.67945 0.3048)
			(stroke
				(width 0.1)
				(type default)
			)
			(layer "F.Fab")
		)
		(fp_line
			(start 0.12065 -0.2794)
			(end 0.12065 -0.3048)
			(stroke
				(width 0.1)
				(type default)
			)
			(layer "F.Fab")
		)
		(fp_line
			(start 0.12065 -0.3048)
			(end 0.67945 -0.3048)
			(stroke
				(width 0.1)
				(type default)
			)
			(layer "F.Fab")
		)
		(fp_line
			(start 0.120396 0.3048)
			(end 0.120396 0.2794)
			(stroke
				(width 0.1)
				(type default)
			)
			(layer "F.Fab")
		)
		(fp_line
			(start 0.120396 0.2794)
			(end -0.12065 0.2794)
			(stroke
				(width 0.1)
				(type default)
			)
			(layer "F.Fab")
		)
		(fp_line
			(start -0.12065 0.3048)
			(end -0.67945 0.3048)
			(stroke
				(width 0.1)
				(type default)
			)
			(layer "F.Fab")
		)
		(fp_line
			(start -0.12065 0.2794)
			(end -0.12065 0.3048)
			(stroke
				(width 0.1)
				(type default)
			)
			(layer "F.Fab")
		)
		(fp_line
			(start -0.12065 -0.2794)
			(end 0.12065 -0.2794)
			(stroke
				(width 0.1)
				(type default)
			)
			(layer "F.Fab")
		)
		(fp_line
			(start -0.12065 -0.305054)
			(end -0.12065 -0.2794)
			(stroke
				(width 0.1)
				(type default)
			)
			(layer "F.Fab")
		)
		(fp_line
			(start -0.67945 0.3048)
			(end -0.67945 -0.305054)
			(stroke
				(width 0.1)
				(type default)
			)
			(layer "F.Fab")
		)
		(fp_line
			(start -0.67945 -0.305054)
			(end -0.12065 -0.305054)
			(stroke
				(width 0.1)
				(type default)
			)
			(layer "F.Fab")
		)
		(pad "1" smd circle
			(at -0.40005 0 180)
			(size 0 0)
			(layers "F.Cu" "F.Mask" "F.Paste")
			(net "PD_JTAG_BMC_NTRST_N")
		)
		(pad "2" smd circle
			(at 0.40005 0 180)
			(size 0 0)
			(layers "F.Cu" "F.Mask" "F.Paste")
			(net "GND")
		)
	)
	(footprint ""
		(layer "F.Cu")
		(at 100.158296 -423.579798 -90)
		(property "Reference" "U272"
			(at 1.16078 -3.199384 0)
			(unlocked yes)
			(layer "F.SilkS")
			(effects
				(font
					(size 0.7874 0.5842)
					(thickness 0.1524)
				)
				(justify left)
			)
		)
		(property "Value" ""
			(at 0 0 270)
			(layer "F.Fab")
			(effects
				(font
					(size 1.27 1.27)
				)
			)
		)
		(duplicate_pad_numbers_are_jumpers no)
		(fp_line
			(start -3.447796 2.500122)
			(end 3.447796 2.500122)
			(stroke
				(width 0.1524)
				(type default)
			)
			(layer "F.SilkS")
		)
		(fp_line
			(start 3.447796 2.500122)
			(end 3.447796 -2.500122)
			(stroke
				(width 0.1524)
				(type default)
			)
			(layer "F.SilkS")
		)
		(fp_line
			(start 0 -1.016)
			(end -1.484122 -2.500122)
			(stroke
				(width 0.1524)
				(type default)
			)
			(layer "F.SilkS")
		)
		(fp_line
			(start -3.447796 -2.500122)
			(end -3.447796 2.500122)
			(stroke
				(width 0.1524)
				(type default)
			)
			(layer "F.SilkS")
		)
		(fp_line
			(start -1.484122 -2.500122)
			(end -3.447796 -2.500122)
			(stroke
				(width 0.1524)
				(type default)
			)
			(layer "F.SilkS")
		)
		(fp_line
			(start 1.484122 -2.500122)
			(end 0 -1.016)
			(stroke
				(width 0.1524)
				(type default)
			)
			(layer "F.SilkS")
		)
		(fp_line
			(start 3.447796 -2.500122)
			(end 1.484122 -2.500122)
			(stroke
				(width 0.1524)
				(type default)
			)
			(layer "F.SilkS")
		)
		(fp_poly
			(pts
				(xy -4.6609 -2.47396) (xy -3.6449 -1.96596) (xy -4.6609 -1.45796)
			)
			(stroke
				(width 0)
				(type default)
			)
			(fill yes)
			(layer "F.SilkS")
		)
		(fp_line
			(start -1.999996 2.500122)
			(end 1.999996 2.500122)
			(stroke
				(width 0.1)
				(type default)
			)
			(layer "F.Fab")
		)
		(fp_line
			(start 1.999996 2.500122)
			(end 1.999996 -2.500122)
			(stroke
				(width 0.1)
				(type default)
			)
			(layer "F.Fab")
		)
		(fp_line
			(start -1.999996 -2.500122)
			(end -1.999996 2.500122)
			(stroke
				(width 0.1)
				(type default)
			)
			(layer "F.Fab")
		)
		(fp_line
			(start 1.999996 -2.500122)
			(end -1.999996 -2.500122)
			(stroke
				(width 0.1)
				(type default)
			)
			(layer "F.Fab")
		)
		(fp_poly
			(pts
				(xy -4.5974 -2.413) (xy -4.5974 -1.397) (xy -3.5814 -1.905)
			)
			(stroke
				(width 0)
				(type default)
			)
			(fill yes)
			(layer "F.Fab")
		)
		(pad "1" smd rect
			(at -2.649982 -1.905 180)
			(size 0.6096 1.3208)
			(layers "F.Cu" "F.Mask" "F.Paste")
			(net "SMB_LM75_2_3V3AUX_SDA_R1")
		)
		(pad "2" smd rect
			(at -2.649982 -0.635 180)
			(size 0.6096 1.3208)
			(layers "F.Cu" "F.Mask" "F.Paste")
			(net "SMB_LM75_2_3V3AUX_SCL_R1")
		)
		(pad "3" smd rect
			(at -2.649982 0.635 180)
			(size 0.6096 1.3208)
			(layers "F.Cu" "F.Mask" "F.Paste")
			(net "FM_LM75_2_ALERT_N")
		)
		(pad "4" smd rect
			(at -2.649982 1.905 180)
			(size 0.6096 1.3208)
			(layers "F.Cu" "F.Mask" "F.Paste")
			(net "GND")
		)
		(pad "5" smd rect
			(at 2.649982 1.905 180)
			(size 0.6096 1.3208)
			(layers "F.Cu" "F.Mask" "F.Paste")
			(net "U272_2_ADD2")
		)
		(pad "6" smd rect
			(at 2.649982 0.635 180)
			(size 0.6096 1.3208)
			(layers "F.Cu" "F.Mask" "F.Paste")
			(net "U272_2_ADD1")
		)
		(pad "7" smd rect
			(at 2.649982 -0.635 180)
			(size 0.6096 1.3208)
			(layers "F.Cu" "F.Mask" "F.Paste")
			(net "U272_2_ADD0")
		)
		(pad "8" smd rect
			(at 2.649982 -1.905 180)
			(size 0.6096 1.3208)
			(layers "F.Cu" "F.Mask" "F.Paste")
			(net "P3V3_AUX")
		)
	)
)
